FILE_TYPE = CONNECTIVITY;
{Allegro Design Entry HDL 16.6-p007 (v16-6-112F) 10/10/2012}
"PAGE_NUMBER" = 146;
0"NC";
1"LPC_LAD_IO<3:0>";
2"P3V3\g";
3"GND\g";
4"GND\g";
5"GND\g";
6"GND\g";
7"RST_PLTRST_BUF_N";
8"SPI_BMC_BT_CS_N";
9"FM_MP_PS_REDUNDANT_LOST_N";
10"FM_POST_CARD_PRES_BMC_N"CDS_PHYS_NET_NAME"FM_POST_CARD_PRES_BMC_N";
11"FM_PE_BMC_WAKE_N";
12"BMC_PRDY_N"CDS_PHYS_NET_NAME"BMC_PRDY_N";
13"RST_BMC_PLTRST_BUF_N";
14"XDP_PRESENT_N";
15"BMC_VGA_VSYNC";
16"CLK_24M_BMC_LPC";
17"BMC_STRAP_BIT18";
18"FM_BMC_NMI_N_R";
19"FM_BMC_NMI_N";
20"IRQ_LOM_ALERT_N";
21"UV_HIGH_SET"CDS_PHYS_NET_NAME"BMC_UV_HIGH_SET";
22"PECI_SEL";
23"FM_TPM_PRES_N"CDS_PHYS_NET_NAME"FM_TPM_PRES_N";
24"RST_BMC_EXTRST_N";
25"SPI_BMC_BT_DO";
26"SPI_BMC_BT_DI";
27"FM_BIOS_POST_CMPLT_N";
28"IRQ_BMC_PCH_SCI_LPC_N";
29"IRQ_PVDDQ_DEF_VRHOT_LVT3_N"$PHYS_NET_NAME"IRQ_PVDDQ_DEF_VRHOT_LVT3_N"CDS_PHYS_NET_NAME"IRQ_PVDDQ_DEF_VRHOT_LVT3_N";
30"FM_BMC_CPLD_GPO"PHYS_NET_NAME"FM_BMC_CPLD_GPO"CDS_PHYS_NET_NAME"FM_BMC_CPLD_GPO";
31"FM_THROTTLE_N";
32"BMC_VGA_HSYNC";
33"IRQ_LPC_SERIRQ_N";
34"LPC_LAD3_IO3_R";
35"LPC_LAD0_IO0_R";
36"LPC_LAD1_IO1_R";
37"FM_OCP_MEZZA_PRES";
38"BMC_SELF_HW_RST"CDS_PHYS_NET_NAME"BMC_SELF_HW_RST";
39"IRQ_HSC_FAULT_N"PHYS_NET_NAME"IRQ_HSC_FAULT_N"CDS_PHYS_NET_NAME"IRQ_HSC_FAULT_N";
40"LPC_LFRAME_N_CS0_R_N";
41"LPC_LAD2_IO2_R";
42"IRQ_LPC_SERIRQ_R";
43"RST_BMC_LVC3_N";
44"I2C_BMC_VGA_DDC_SCL";
45"I2C_BMC_VGA_DDC_SDA";
46"SPI_BMC_BT_CLK_R";
47"PD_SP_ENTEST";
48"FM_BMC_READY_N";
49"IRQ_SML0_ALERT_N";
50"HSC_SMBUS_SWITCH_EN";
51"BMC_STRAP_BIT20";
52"BMC_STRAP_BIT27";
53"FM_CPU1_SKTOCC_LVT3_N";
54"FP_PWR_ID_LED_N";
55"IRQ_SML1_PMBUS_ALERT_N";
56"BMC_STRAP_BIT17";
57"GPIOS7";
58"BMC_STRAP_BIT5";
59"BMC_STRAP_BIT3"CDS_PHYS_NET_NAME"H_CPU0_MEMDEF_MEMHOT_LVT3_BMC_N";
60"SPI_BMC_BT_CS_R_N";
61"A_USB2AVRES";
62"BMC_TCK_MUX_SEL"CDS_PHYS_NET_NAME"BMC_TCK_MUX_SEL";
63"FM_BMC_HEARTBEAT_N";
64"BMC_M_RST_N";
65"BMC_M_MALERT_N";
66"A_USB2BVRES";
67"LED_POSTCODE_7";
68"LED_POSTCODE_4";
69"LED_POSTCODE_0";
70"LED_POSTCODE_1";
71"LED_POSTCODE_3";
72"LED_POSTCODE_5";
73"USB_PCH_BMC_P4_DN";
74"RST_PLTRST_BUF_N";
75"LPC_LFRAME_N_CS0_N";
76"I2C_BMC_VGA_DDC_SCL";
77"I2C_BMC_VGA_DDC_SDA";
78"LPC_LAD_IO<0>";
79"LPC_LAD_IO<1>";
80"LPC_LAD_IO<2>";
81"LPC_LAD_IO<3>";
82"LED_POSTCODE_2";
83"USB2_PCH_BMC_P5_DP";
84"USB2_PCH_BMC_P5_DN";
85"USB_PCH_BMC_P4_DP";
86"LED_POSTCODE_6";
87"SPI_BMC_BT_DO_R";
88"SPI_BMC_BT_CLK";
89"SPI_BMC_BT_CS0_N"CDS_PHYS_NET_NAME"SPI_BMC_BT_CS1_N";
%"AST2520A1-GP-GP"
"4","(-3875,4000)","0","w_hdl","I104";
;
CDS_SEC"4"
$SEC"4"
CDS_LOCATION"U25W4"
VALUE"AST2520A1-GP-GP"
LOCATION"U25W4"
PART_NUMBER"071.2520A.M001"
PACK_TYPE"ASIC2-GB1"
CDS_LIB"w_hdl"
CDS_LMAN_SYM_OUTLINE"-1350,800,1350,-800";
"GPIOAA3_VPOR5_NORD3_SALT10"
$PN"AA22"23;
"GPIOAA4_VPOR6_NORD4_SALT11"
$PN"U22"22;
"GPIOAA5_VPOR7_NORD5_SALT12"
$PN"T20"21;
"GPIOAA6_VPOR8_NORD6_SALT13"
$PN"N18"20;
"GPIOAA7_VPOR9_NORD7_SALT14"
$PN"P19"27;
"GPIOAA1_VPOR3_NORD1_SALT8"
$PN"V21"55;
"GPIOS1_VPOB3_BMCINT"
$PN"U19"48;
"GPIOS4_VPOB6"
$PN"R19"59;
"GPIOS5_VPOB7"
$PN"W20"0;
"GPIOS6_VPOB8"
$PN"U20"58;
"USB2B_DN"
$PN"A6"84;
"USB2B_DP"
$PN"B6"83;
"USB2A_DN"
$PN"A8"73;
"USB2A_DP"
$PN"A7"85;
"GPIOAA2_VPOR4_NORD2_SALT9"
$PN"Y22"54;
"GPIOZ0_VPOG2_NORA0_SIOPBI# \B"
$PN"Y20"30;
"GPIOS7_VPOB9"
$PN"AA20"57;
"GPIOS3_VPOB5_SALT6"
$PN"P18"50;
"GPIOAA0_VPOR2_NORD0_SALT7"
$PN"Y21"53;
"GPIOZ7_VPOG9_NORA7"
$PN"W21"52;
"GPIOZ6_VPOG8_NORA6"
$PN"V22"51;
"GPIOZ5_VPOG7_NORA5"
$PN"W22"17;
"GPIOZ4_VPOG6_NORA4"
$PN"U21"56;
"GPIOZ3_VPOG5_NORA3_SIOSCI# \B"
$PN"AA21"28;
"GPIOZ2_VPOG4_NORA2_SIOPBO# \B"
$PN"AB21"29;
"GPIOZ1_VPOG3_NORA1_SIOPWRGD"
$PN"AB20"18;
"GPIOS2_VPOB4_SALT5"
$PN"R18"49;
"GPIOS0_VPOB2_SPI2CS1# \B"
$PN"V20"31;
"GPIOH6_TXD6"
$PN"A16"86;
"GPIOH7_RXD6"
$PN"D18"67;
"GPIOH5_NRTS6"
$PN"B17"72;
"GPIOH3_NRI6"
$PN"C17"71;
"GPIOH4_NDTR6"
$PN"A17"68;
"GPIOH1_NDCD6"
$PN"B18"70;
"GPIOH2_NDSR6"
$PN"D17"82;
"GPIOH0_NCTS6"
$PN"A18"69;
"USB2AVRES"
$PN"B8"61;
"USB2BVRES"
$PN"B7"66;
%"AST2520A1-GP-GP"
"5","(-4025,1850)","0","w_hdl","I105";
;
CDS_SEC"5"
$SEC"5"
CDS_LOCATION"U25W4"
VALUE"AST2520A1-GP-GP"
LOCATION"U25W4"
CDS_LMAN_SYM_OUTLINE"-1325,950,1325,-950"
PACK_TYPE"ASIC2-GB1"
PART_NUMBER"071.2520A.M001"
CDS_LIB"w_hdl";
"GPIOR4_SPI2MOSI"
$PN"W19"14;
"GPIOR3_SPI2CK"
$PN"Y19"12;
"GPIOAC5_ESPICS#_LFRAME# \B"
$PN"F21"40;
"GPIOAC6_ESPIALT#_LSIRQ# \B"
$PN"F22"42;
"FWSPICS0# \B"
$PN"AB19"89;
"FWSPIMISO"
$PN"T18"26;
"GPIOAC0_ESPID0_LAD0"
$PN"G21"35;
"GPIOAC1_ESPID1_LAD1"
$PN"G20"36;
"GPIOAC2_ESPID2_LAD2"
$PN"D22"41;
"GPIOAC3_ESPID3_LAD3"
$PN"E22"34;
"GPIOAC4_ESPICK_LCLK"
$PN"C22"16;
"GPIOAB0_VPODE_NOROE# \B"
$PN"N19"39;
"GPIOAB1_VPOHS_NORWE# \B"
$PN"T21"37;
"GPIOAB2_VPOVS_WDTRST1"
$PN"T22"38;
"GPIOAB3_VPOCLK_WDTRST2"
$PN"R20"0;
"GPIOJ5_VGAVS"
$PN"R4"15;
"GPIOJ6_DDCCLK"
$PN"R3"44;
"GPIOJ7_DDCDAT"
$PN"T3"45;
"FWSPICK"
$PN"AA18"46;
"FWSPIMOSI"
$PN"U17"87;
"GPIOJ4_VGAHS"
$PN"N5"32;
"HBLED# \B"
$PN"Y18"63;
"MALERT# \B"
$PN"U16"65;
"MRESET# \B"
$PN"AB17"64;
"GPIOR0_FWSPICS1# \B"
$PN"AA19"60;
"GPIOR1_FWSPICS2# \B"
$PN"T19"9;
"GPIOR2_SPI2CS0# \B"
$PN"T17"62;
"GPIOR5_SPI2MISO"
$PN"V19"13;
"GPIOQ7_PEWAKE# \B"
$PN"N20"11;
"GPIOQ6_OSCCLK"
$PN"B10"10;
"EXTRST# \B"
$PN"V18"24;
"ENTEST"
$PN"K3"47;
"GPIOAC7_ESPIRST#_LPCRST# \B"
$PN"G22"43;
%"RES"
"1","(-1450,2050)","0","mstr_discrete","I123";
;
TOLERANCE"1.0%"
MATERIAL"CHIP"
VALUE"22.1"
LOCATION"R25W78"
PART_NUMBER"G21796-250"
WATTAGE"1/16W"
PACK_TYPE"0402"
CDS_SEC"1"
CDS_LOCATION"R25W78"
CDS_LIB"mstr_discrete"
SEC_TYPE"0402"
SEC"1"
ROOM"BMC"
BOM_COST"SM_CONTROLLER";
"B"
$PN"2"8;
"A"
$PN"1"60;
%"RES"
"2","(-7300,400)","1","mstr_discrete","I152";
;
WATTAGE"1/16W"
TOLERANCE"1%"
MATERIAL"CHIP"
LOCATION"R25W129"
PACK_TYPE"0402"
PART_NUMBER"G21796-072"
VALUE"4.75K"
CDS_LOCATION"R25W129"
CDS_SEC"1"
CDS_LIB"mstr_discrete"
ROOM"CPU_FANS"
SEC"1"
SEC_TYPE"0402"
BOM_COST"SM_THERM";
"A"
$PN"1"2;
"B"
$PN"2"76;
%"RES"
"2","(-7300,250)","1","mstr_discrete","I153";
;
PACK_TYPE"0402"
LOCATION"R25W130"
VALUE"4.75K"
WATTAGE"1/16W"
MATERIAL"CHIP"
PART_NUMBER"G21796-072"
TOLERANCE"1%"
CDS_LOCATION"R25W130"
BOM_COST"SM_THERM"
SEC_TYPE"0402"
SEC"1"
ROOM"CPU_FANS"
CDS_LIB"mstr_discrete"
CDS_SEC"1";
"A"
$PN"1"2;
"B"
$PN"2"77;
%"P3V3"
"1","(-7550,500)","0","mstr_symbols","I154";
;
HDL_POWER"P3V3"
BODY_TYPE"PLUMBING"
CDS_LIB"mstr_symbols"
SIZE"1B"
VOLTAGE"3.3V";
"G\NAC"2;
%"CAP"
"1","(-550,4350)","1","mstr_discrete","I160";
;
CDS_SEC"1"
TOLERANCE"10%"
MATERIAL"X7R"
LOCATION"C1W21"
VALUE"0.033UF"
PART_NUMBER"603269-064"
PACK_TYPE"0603LF"
VOLTAGE"50V"
CDS_LIB"mstr_discrete"
ROOM"HOT_SWAP"
SEC"1"
SEC_TYPE"0603LF"
CDS_LOCATION"C1W21";
"A"
$PN"1"61;
"B"
$PN"2"3;
%"RES"
"1","(-1600,1800)","0","mstr_discrete","I166";
;
TOLERANCE"5%"
WATTAGE"1/16W"
PART_NUMBER"G21497-005"
PACK_TYPE"0402"
VALUE"0.0"
LOCATION"R25W184"
MATERIAL"CHIP"
ROOM"BMC"
BOM_COST"SM_CONTROLLER"
SEC_TYPE"0402"
SEC"1"
CDS_SEC"1"
CDS_LIB"mstr_discrete"
CDS_LOCATION"R25W184";
"B"
$PN"2"7;
"A"
$PN"1"13;
%"RES"
"1","(-6900,3900)","0","mstr_discrete","I26";
;
CDS_SEC"1"
CDS_LOCATION"R25W83"
MATERIAL"CHIP"
PACK_TYPE"0402"
TOLERANCE"5%"
PART_NUMBER"G21497-005"
WATTAGE"1/16W"
VALUE"0.0"
LOCATION"R25W83"
SEC"1"
SEC_TYPE"0402"
CDS_LIB"mstr_discrete"
ROOM"USB"
BOM_COST"MIO_USB";
"B"
$PN"2"18;
"A"
$PN"1"19;
%"RES"
"2","(-850,4150)","1","mstr_discrete","I35";
;
CDS_SEC"1"
CDS_LOCATION"R1T25"
PACK_TYPE"0402"
MATERIAL"CHIP"
WATTAGE"1/16W"
TOLERANCE"1%"
VALUE"8.2K"
LOCATION"R1T25"
PART_NUMBER"G21796-345"
ROOM"BMC"
BOM_COST"SM_CONTROLLER"
CDS_LIB"mstr_discrete"
SEC_TYPE"0402"
SEC"1";
"A"
$PN"1"66;
"B"
$PN"2"3;
%"GND"
"1","(-300,4200)","1","mstr_symbols","I36";
;
HDL_POWER"GND"
BODY_TYPE"PLUMBING"
VOLTAGE"0.0V"
CDS_LIB"mstr_symbols"
SIZE"1B";
"A\NAC"3;
%"RES"
"2","(-550,4200)","1","mstr_discrete","I37";
;
CDS_SEC"1"
TOLERANCE"1%"
PART_NUMBER"G21796-345"
PACK_TYPE"0402"
WATTAGE"1/16W"
MATERIAL"CHIP"
VALUE"8.2K"
LOCATION"R1T26"
SEC"1"
SEC_TYPE"0402"
CDS_LIB"mstr_discrete"
ROOM"BMC"
BOM_COST"SM_CONTROLLER"
CDS_LOCATION"R1T26";
"A"
$PN"1"61;
"B"
$PN"2"3;
%"RES"
"2","(-1550,1400)","0","mstr_discrete","I65";
;
PACK_TYPE"0402"
TOLERANCE"1%"
WATTAGE"1/16W"
MATERIAL"CHIP"
PART_NUMBER"G21796-010"
VALUE"100.0K"
LOCATION"R25W63"
CDS_LOCATION"R25W63"
CDS_SEC"1"
CDS_LIB"mstr_discrete"
SEC"1"
SEC_TYPE"0402"
BOM_COST"SM_CONTROLLER"
ROOM"BMC";
"A"
$PN"1"11;
"B"
$PN"2"4;
%"GND"
"1","(-1550,1200)","0","mstr_symbols","I66";
;
HDL_POWER"GND"
BODY_TYPE"PLUMBING"
SIZE"1B"
VOLTAGE"0.0V"
CDS_LIB"mstr_symbols";
"A\NAC"4;
%"RES"
"1","(-6350,2350)","0","mstr_discrete","I67";
;
CDS_SEC"1"
LOCATION"R25W81"
WATTAGE"1/16W"
MATERIAL"CHIP"
VALUE"33.2"
PACK_TYPE"0402"
PART_NUMBER"G21796-074"
TOLERANCE"1%"
CDS_LOCATION"R25W81"
CDS_LIB"mstr_discrete"
SEC_TYPE"0402"
SEC"1"
ROOM"BMC"
BOM_COST"SM_CONTROLLER";
"B"
$PN"2"46;
"A"
$PN"1"88;
%"RES"
"1","(-6350,2500)","0","mstr_discrete","I68";
;
CDS_SEC"1"
WATTAGE"1/16W"
TOLERANCE"1%"
VALUE"33.2"
PART_NUMBER"G21796-074"
LOCATION"R25W82"
MATERIAL"CHIP"
PACK_TYPE"0402"
CDS_LOCATION"R25W82"
CDS_LIB"mstr_discrete"
ROOM"BMC"
BOM_COST"SM_CONTROLLER"
SEC_TYPE"0402"
SEC"1";
"B"
$PN"2"87;
"A"
$PN"1"25;
%"RES"
"1","(-6350,1750)","0","mstr_discrete","I70";
;
TOLERANCE"5%"
PART_NUMBER"G21497-005"
MATERIAL"CHIP"
WATTAGE"1/16W"
VALUE"0.0"
PACK_TYPE"0402"
LOCATION"R25W74"
ROOM"BMC"
BOM_COST"SM_CONTROLLER"
SEC_TYPE"0402"
SEC"1"
CDS_LOCATION"R25W74"
CDS_SEC"1"
CDS_LIB"mstr_discrete";
"B"
$PN"2"43;
"A"
$PN"1"74;
%"RES"
"1","(-6350,1550)","0","mstr_discrete","I71";
;
MATERIAL"CHIP"
PACK_TYPE"0402"
WATTAGE"1/16W"
TOLERANCE"1%"
LOCATION"R25W72"
VALUE"33.2"
PART_NUMBER"G21796-074"
CDS_LOCATION"R25W72"
BOM_COST"SM_CONTROLLER"
SEC_TYPE"0402"
SEC"1"
ROOM"BMC"
CDS_LIB"mstr_discrete"
CDS_SEC"1";
"B"
$PN"2"40;
"A"
$PN"1"75;
%"RES"
"1","(-6350,1650)","0","mstr_discrete","I73";
;
VALUE"33.2"
PACK_TYPE"0402"
TOLERANCE"1%"
PART_NUMBER"G21796-074"
WATTAGE"1/16W"
MATERIAL"CHIP"
LOCATION"R25W73"
CDS_LOCATION"R25W73"
SEC_TYPE"0402"
BOM_COST"SM_CONTROLLER"
SEC"1"
ROOM"BMC"
CDS_LIB"mstr_discrete"
CDS_SEC"1";
"B"
$PN"2"42;
"A"
$PN"1"33;
%"RES"
"1","(-6850,1350)","0","mstr_discrete","I74";
;
CDS_SEC"1"
CDS_LOCATION"R3N24"
LOCATION"R3N24"
TOLERANCE"1%"
PART_NUMBER"G21796-074"
PACK_TYPE"0402"
VALUE"33.2"
MATERIAL"CHIP"
WATTAGE"1/16W"
SEC"1"
SEC_TYPE"0402"
ROOM"BMC"
BOM_COST"SB"
CDS_LIB"mstr_discrete";
"B"
$PN"2"41;
"A"
$PN"1"80;
%"RES"
"1","(-6850,1250)","0","mstr_discrete","I75";
;
CDS_SEC"1"
CDS_LOCATION"R3N26"
PACK_TYPE"0402"
PART_NUMBER"G21796-074"
WATTAGE"1/16W"
LOCATION"R3N26"
VALUE"33.2"
TOLERANCE"1%"
MATERIAL"CHIP"
SEC"1"
SEC_TYPE"0402"
ROOM"BMC"
BOM_COST"SB"
CDS_LIB"mstr_discrete";
"B"
$PN"2"35;
"A"
$PN"1"78;
%"RES"
"2","(-6250,850)","0","mstr_discrete","I76";
;
WATTAGE"1/16W"
VALUE"100.0K"
PACK_TYPE"0402"
TOLERANCE"1%"
MATERIAL"CHIP"
PART_NUMBER"G21796-010"
POP"NOPOP"
LOCATION"R25W66"
CDS_SEC"1"
$SEC"1"
ROOM"BMC"
CDS_LIB"mstr_discrete"
CDS_LOCATION"R25W66";
"A"
$PN"1"16;
"B"
$PN"2"5;
%"GND"
"1","(-6250,650)","0","mstr_symbols","I77";
;
HDL_POWER"GND"
BODY_TYPE"PLUMBING"
VOLTAGE"0.0V"
CDS_LIB"mstr_symbols"
SIZE"1B";
"A\NAC"5;
%"RES"
"1","(-6350,2650)","0","mstr_discrete","I78";
;
LOCATION"R1U7"
VALUE"10.0K"
PART_NUMBER"G21796-016"
MATERIAL"CHIP"
PACK_TYPE"0402"
WATTAGE"1/16W"
TOLERANCE"1%"
CDS_LOCATION"R1U7"
CDS_LIB"mstr_discrete"
BOM_COST"SM_CONTROLLER"
ROOM"BMC"
SEC_TYPE"0402"
SEC"1"
CDS_SEC"1";
"B"
$PN"2"47;
"A"
$PN"1"6;
%"GND"
"1","(-6650,2650)","5","mstr_symbols","I79";
;
HDL_POWER"GND"
BODY_TYPE"PLUMBING"
CDS_LIB"mstr_symbols"
SIZE"1B"
VOLTAGE"0.0V";
"A\NAC"6;
%"RES"
"1","(-6850,1400)","0","mstr_discrete","I84";
;
CDS_SEC"1"
CDS_LOCATION"R25W68"
TOLERANCE"1%"
VALUE"33.2"
LOCATION"R25W68"
WATTAGE"1/16W"
PART_NUMBER"G21796-074"
MATERIAL"CHIP"
PACK_TYPE"0402"
CDS_LIB"mstr_discrete"
BOM_COST"SB"
ROOM"BMC"
SEC_TYPE"0402"
SEC"1";
"B"
$PN"2"34;
"A"
$PN"1"81;
%"RES"
"1","(-6850,1300)","0","mstr_discrete","I85";
;
CDS_SEC"1"
CDS_LOCATION"R25W69"
LOCATION"R25W69"
PART_NUMBER"G21796-074"
WATTAGE"1/16W"
PACK_TYPE"0402"
VALUE"33.2"
TOLERANCE"1%"
MATERIAL"CHIP"
ROOM"BMC"
BOM_COST"SB"
CDS_LIB"mstr_discrete"
SEC_TYPE"0402"
SEC"1";
"B"
$PN"2"36;
"A"
$PN"1"79;
%"TAP"
"1","(-7050,1400)","2","mstr_standard","I90";
;
HDL_TAP"TRUE"
BODY_TYPE"PLUMBING"
CDS_LIB"mstr_standard";
"B \NAC \NWC"1;
"S \NAC"
BN"3"81;
%"TAP"
"1","(-7050,1250)","2","mstr_standard","I91";
;
HDL_TAP"TRUE"
BODY_TYPE"PLUMBING"
CDS_LIB"mstr_standard";
"B \NAC \NWC"1;
"S \NAC"
BN"0"78;
%"TAP"
"1","(-7050,1300)","2","mstr_standard","I92";
;
HDL_TAP"TRUE"
BODY_TYPE"PLUMBING"
CDS_LIB"mstr_standard";
"B \NAC \NWC"1;
"S \NAC"
BN"1"79;
%"TAP"
"1","(-7050,1350)","2","mstr_standard","I93";
;
HDL_TAP"TRUE"
BODY_TYPE"PLUMBING"
CDS_LIB"mstr_standard";
"B \NAC \NWC"1;
"S \NAC"
BN"2"80;
END.
